# S9S_MB_2U (Grand Teton) — schematic netlist excerpt (pin names and nets, part order shuffled) for the footprints in the layout excerpt that follows; sources: Cadence DE-HDL packaged netlist, KiCad conversion of 03242023_DA0F0TMBIJ0_F0T_Motherboard_J_brd_V01_OCP.brd

R1023  Q_RES  0 5% CHIP  pkg 0402LF  page 209 : A = CLK_25M_CK440_CPU1_R_DN ; B = CLK_25M_NSSC_CPU1_DN
PR2554  Q_RES  0.03 0.1% EMPTY  pkg 2512LF  page 267 : A = P12V_AUX ; B = SW_P12V_PVCCIN_CPU0_FLT
R1227  Q_RES  10K 1% CHIP  pkg 0402LF  page 43 : A = PD_JTAG_CPU1_PLD_TCK ; B = GND

(kicad_pcb
	(version 20260206)
	(generator "pcbnew")
	(generator_version "10.0")
	(general
		(thickness 1.6)
		(legacy_teardrops no)
	)
	(paper "A4")
	(title_block
		(title "03242023_DA0F0TMBIJ0_F0T_Motherboard_J_brd_V01_OCP.brd")
		(comment 1 "Grand Teton / footprints 5097-5099 of 6105")
	)
	(layers
		(0 "F.Cu" signal "TOP")
		(4 "In1.Cu" signal "GND")
		(6 "In2.Cu" signal "IN1")
		(8 "In3.Cu" signal "GND1")
		(10 "In4.Cu" signal "IN2")
		(12 "In5.Cu" signal "GND2")
		(14 "In6.Cu" signal "IN3")
		(16 "In7.Cu" signal "GND3")
		(18 "In8.Cu" signal "VCC")
		(20 "In9.Cu" signal "VCC1")
		(22 "In10.Cu" signal "GND4")
		(24 "In11.Cu" signal "IN4")
		(26 "In12.Cu" signal "GND5")
		(28 "In13.Cu" signal "IN5")
		(30 "In14.Cu" signal "GND6")
		(32 "In15.Cu" signal "IN6")
		(34 "In16.Cu" signal "GND7")
		(2 "B.Cu" signal "BOTTOM")
		(9 "F.Adhes" user "F.Adhesive")
		(11 "B.Adhes" user "B.Adhesive")
		(13 "F.Paste" user "Package Geometry/Pastemask Top")
		(15 "B.Paste" user "Package Geometry/Pastemask Bottom")
		(5 "F.SilkS" user "Ref Des/Silkscreen Top")
		(7 "B.SilkS" user "Ref Des/Silkscreen Bottom")
		(1 "F.Mask" user "Board Geometry/Soldermask Top")
		(3 "B.Mask" user "Board Geometry/Soldermask Bottom")
		(17 "Dwgs.User" user "User.Drawings")
		(19 "Cmts.User" user "User.Comments")
		(21 "Eco1.User" user "User.Eco1")
		(23 "Eco2.User" user "User.Eco2")
		(25 "Edge.Cuts" user "Board Geometry/Outline")
		(27 "Margin" user)
		(31 "F.CrtYd" user "Package Geometry/Place Bound Top")
		(29 "B.CrtYd" user "Package Geometry/Place Bound Bottom")
		(35 "F.Fab" user "Ref Des/Assembly Top")
		(33 "B.Fab" user "Ref Des/Assembly Bottom")
	)
	(footprint ""
		(layer "B.Cu")
		(at 236.201712 -135.401558 180)
		(property "Reference" "R1023"
			(at 0 0 0)
			(layer "B.SilkS")
			(hide yes)
			(effects
				(font
					(size 1.27 1.27)
				)
				(justify mirror)
			)
		)
		(property "Value" ""
			(at 0 0 0)
			(layer "B.Fab")
			(effects
				(font
					(size 1.27 1.27)
				)
				(justify mirror)
			)
		)
		(duplicate_pad_numbers_are_jumpers no)
		(fp_line
			(start 0.7874 0.4064)
			(end 0.7874 -0.04191)
			(stroke
				(width 0.1524)
				(type default)
			)
			(layer "B.SilkS")
		)
		(fp_line
			(start 0.652272 -0.4064)
			(end -0.455168 -0.4064)
			(stroke
				(width 0.1524)
				(type default)
			)
			(layer "B.SilkS")
		)
		(fp_line
			(start -0.7874 0.4064)
			(end 0.7874 0.4064)
			(stroke
				(width 0.1524)
				(type default)
			)
			(layer "B.SilkS")
		)
		(fp_line
			(start -0.7874 -0.20955)
			(end -0.7874 0.4064)
			(stroke
				(width 0.1524)
				(type default)
			)
			(layer "B.SilkS")
		)
		(fp_line
			(start 0.67945 0.3048)
			(end 0.67945 -0.305054)
			(stroke
				(width 0.1)
				(type default)
			)
			(layer "B.Fab")
		)
		(fp_line
			(start 0.67945 -0.305054)
			(end 0.12065 -0.305054)
			(stroke
				(width 0.1)
				(type default)
			)
			(layer "B.Fab")
		)
		(fp_line
			(start 0.12065 0.3048)
			(end 0.67945 0.3048)
			(stroke
				(width 0.1)
				(type default)
			)
			(layer "B.Fab")
		)
		(fp_line
			(start 0.12065 0.2794)
			(end 0.12065 0.3048)
			(stroke
				(width 0.1)
				(type default)
			)
			(layer "B.Fab")
		)
		(fp_line
			(start 0.12065 -0.2794)
			(end -0.12065 -0.2794)
			(stroke
				(width 0.1)
				(type default)
			)
			(layer "B.Fab")
		)
		(fp_line
			(start 0.12065 -0.305054)
			(end 0.12065 -0.2794)
			(stroke
				(width 0.1)
				(type default)
			)
			(layer "B.Fab")
		)
		(fp_line
			(start -0.120396 0.3048)
			(end -0.120396 0.2794)
			(stroke
				(width 0.1)
				(type default)
			)
			(layer "B.Fab")
		)
		(fp_line
			(start -0.120396 0.2794)
			(end 0.12065 0.2794)
			(stroke
				(width 0.1)
				(type default)
			)
			(layer "B.Fab")
		)
		(fp_line
			(start -0.12065 -0.2794)
			(end -0.12065 -0.3048)
			(stroke
				(width 0.1)
				(type default)
			)
			(layer "B.Fab")
		)
		(fp_line
			(start -0.12065 -0.3048)
			(end -0.67945 -0.3048)
			(stroke
				(width 0.1)
				(type default)
			)
			(layer "B.Fab")
		)
		(fp_line
			(start -0.67945 0.3048)
			(end -0.120396 0.3048)
			(stroke
				(width 0.1)
				(type default)
			)
			(layer "B.Fab")
		)
		(fp_line
			(start -0.67945 -0.3048)
			(end -0.67945 0.3048)
			(stroke
				(width 0.1)
				(type default)
			)
			(layer "B.Fab")
		)
		(pad "1" smd rect
			(at 0.40005 0 180)
			(size 0.4572 0.508)
			(layers "B.Cu" "B.Mask" "B.Paste")
			(net "CLK_25M_CK440_CPU1_R_DN")
		)
		(pad "2" smd rect
			(at -0.40005 0 180)
			(size 0.4572 0.508)
			(layers "B.Cu" "B.Mask" "B.Paste")
			(net "CLK_25M_NSSC_CPU1_DN")
		)
	)
	(footprint ""
		(layer "B.Cu")
		(at 155.356052 -196.776848 180)
		(property "Reference" "R1227"
			(at 0 0 0)
			(layer "B.SilkS")
			(hide yes)
			(effects
				(font
					(size 1.27 1.27)
				)
				(justify mirror)
			)
		)
		(property "Value" ""
			(at 0 0 0)
			(layer "B.Fab")
			(effects
				(font
					(size 1.27 1.27)
				)
				(justify mirror)
			)
		)
		(duplicate_pad_numbers_are_jumpers no)
		(fp_line
			(start 0.7874 0.4064)
			(end 0.7874 -0.4064)
			(stroke
				(width 0.1524)
				(type default)
			)
			(layer "B.SilkS")
		)
		(fp_line
			(start 0.7874 -0.4064)
			(end -0.7874 -0.4064)
			(stroke
				(width 0.1524)
				(type default)
			)
			(layer "B.SilkS")
		)
		(fp_line
			(start -0.7874 0.4064)
			(end 0.7874 0.4064)
			(stroke
				(width 0.1524)
				(type default)
			)
			(layer "B.SilkS")
		)
		(fp_line
			(start -0.7874 -0.4064)
			(end -0.7874 0.4064)
			(stroke
				(width 0.1524)
				(type default)
			)
			(layer "B.SilkS")
		)
		(fp_line
			(start 0.67945 0.3048)
			(end 0.67945 -0.305054)
			(stroke
				(width 0.1)
				(type default)
			)
			(layer "B.Fab")
		)
		(fp_line
			(start 0.67945 -0.305054)
			(end 0.12065 -0.305054)
			(stroke
				(width 0.1)
				(type default)
			)
			(layer "B.Fab")
		)
		(fp_line
			(start 0.12065 0.3048)
			(end 0.67945 0.3048)
			(stroke
				(width 0.1)
				(type default)
			)
			(layer "B.Fab")
		)
		(fp_line
			(start 0.12065 0.2794)
			(end 0.12065 0.3048)
			(stroke
				(width 0.1)
				(type default)
			)
			(layer "B.Fab")
		)
		(fp_line
			(start 0.12065 -0.2794)
			(end -0.12065 -0.2794)
			(stroke
				(width 0.1)
				(type default)
			)
			(layer "B.Fab")
		)
		(fp_line
			(start 0.12065 -0.305054)
			(end 0.12065 -0.2794)
			(stroke
				(width 0.1)
				(type default)
			)
			(layer "B.Fab")
		)
		(fp_line
			(start -0.120396 0.3048)
			(end -0.120396 0.2794)
			(stroke
				(width 0.1)
				(type default)
			)
			(layer "B.Fab")
		)
		(fp_line
			(start -0.120396 0.2794)
			(end 0.12065 0.2794)
			(stroke
				(width 0.1)
				(type default)
			)
			(layer "B.Fab")
		)
		(fp_line
			(start -0.12065 -0.2794)
			(end -0.12065 -0.3048)
			(stroke
				(width 0.1)
				(type default)
			)
			(layer "B.Fab")
		)
		(fp_line
			(start -0.12065 -0.3048)
			(end -0.67945 -0.3048)
			(stroke
				(width 0.1)
				(type default)
			)
			(layer "B.Fab")
		)
		(fp_line
			(start -0.67945 0.3048)
			(end -0.120396 0.3048)
			(stroke
				(width 0.1)
				(type default)
			)
			(layer "B.Fab")
		)
		(fp_line
			(start -0.67945 -0.3048)
			(end -0.67945 0.3048)
			(stroke
				(width 0.1)
				(type default)
			)
			(layer "B.Fab")
		)
		(pad "1" smd circle
			(at 0.40005 0)
			(size 0 0)
			(layers "B.Cu" "B.Mask" "B.Paste")
			(net "PD_JTAG_CPU1_PLD_TCK")
		)
		(pad "2" smd circle
			(at -0.40005 0)
			(size 0 0)
			(layers "B.Cu" "B.Mask" "B.Paste")
			(net "GND")
		)
	)
	(footprint ""
		(layer "B.Cu")
		(at 340.036658 -354.92817 90)
		(property "Reference" "PR2554"
			(at 0 0 90)
			(layer "B.SilkS")
			(hide yes)
			(effects
				(font
					(size 1.27 1.27)
				)
				(justify mirror)
			)
		)
		(property "Value" ""
			(at 0 0 90)
			(layer "B.Fab")
			(effects
				(font
					(size 1.27 1.27)
				)
				(justify mirror)
			)
		)
		(duplicate_pad_numbers_are_jumpers no)
		(fp_line
			(start 4.0386 -1.7526)
			(end -4.0386 -1.7526)
			(stroke
				(width 0.1524)
				(type default)
			)
			(layer "B.SilkS")
		)
		(fp_line
			(start -4.0386 -1.7526)
			(end -4.0386 1.7526)
			(stroke
				(width 0.1524)
				(type default)
			)
			(layer "B.SilkS")
		)
		(fp_line
			(start 4.0386 1.7526)
			(end 4.0386 -1.7526)
			(stroke
				(width 0.1524)
				(type default)
			)
			(layer "B.SilkS")
		)
		(fp_line
			(start -4.0386 1.7526)
			(end 4.0386 1.7526)
			(stroke
				(width 0.1524)
				(type default)
			)
			(layer "B.SilkS")
		)
		(fp_line
			(start 4.0386 -1.7526)
			(end -4.0386 -1.7526)
			(stroke
				(width 0.1)
				(type default)
			)
			(layer "B.Fab")
		)
		(fp_line
			(start -4.0386 -1.7526)
			(end -4.0386 1.7526)
			(stroke
				(width 0.1)
				(type default)
			)
			(layer "B.Fab")
		)
		(fp_line
			(start 4.0386 1.7526)
			(end 4.0386 -1.7526)
			(stroke
				(width 0.1)
				(type default)
			)
			(layer "B.Fab")
		)
		(fp_line
			(start -4.0386 1.7526)
			(end 4.0386 1.7526)
			(stroke
				(width 0.1)
				(type default)
			)
			(layer "B.Fab")
		)
		(pad "1" smd rect
			(at 3.1115 0 270)
			(size 1.524 3.2004)
			(layers "B.Cu" "B.Mask" "B.Paste")
			(net "P12V_AUX")
		)
		(pad "2" smd rect
			(at -3.1115 0 270)
			(size 1.524 3.2004)
			(layers "B.Cu" "B.Mask" "B.Paste")
			(net "SW_P12V_PVCCIN_CPU0_FLT")
		)
	)
)
